(kicad_pcb
	(version 20260206)
	(generator "pcbnew")
	(generator_version "10.0")
	(general
		(thickness 1.6)
		(legacy_teardrops no)
	)
	(paper "A4")
	(title_block
		(title "03242023_DA0F0TMBIJ0_F0T_Motherboard_J_brd_V01_OCP.brd")
		(comment 1 "Grand Teton / footprints 574-579 of 6105")
	)
	(layers
		(0 "F.Cu" signal "TOP")
		(4 "In1.Cu" signal "GND")
		(6 "In2.Cu" signal "IN1")
		(8 "In3.Cu" signal "GND1")
		(10 "In4.Cu" signal "IN2")
		(12 "In5.Cu" signal "GND2")
		(14 "In6.Cu" signal "IN3")
		(16 "In7.Cu" signal "GND3")
		(18 "In8.Cu" signal "VCC")
		(20 "In9.Cu" signal "VCC1")
		(22 "In10.Cu" signal "GND4")
		(24 "In11.Cu" signal "IN4")
		(26 "In12.Cu" signal "GND5")
		(28 "In13.Cu" signal "IN5")
		(30 "In14.Cu" signal "GND6")
		(32 "In15.Cu" signal "IN6")
		(34 "In16.Cu" signal "GND7")
		(2 "B.Cu" signal "BOTTOM")
		(9 "F.Adhes" user "F.Adhesive")
		(11 "B.Adhes" user "B.Adhesive")
		(13 "F.Paste" user "Package Geometry/Pastemask Top")
		(15 "B.Paste" user "Package Geometry/Pastemask Bottom")
		(5 "F.SilkS" user "Ref Des/Silkscreen Top")
		(7 "B.SilkS" user "Ref Des/Silkscreen Bottom")
		(1 "F.Mask" user "Board Geometry/Soldermask Top")
		(3 "B.Mask" user "Board Geometry/Soldermask Bottom")
		(17 "Dwgs.User" user "User.Drawings")
		(19 "Cmts.User" user "User.Comments")
		(21 "Eco1.User" user "User.Eco1")
		(23 "Eco2.User" user "User.Eco2")
		(25 "Edge.Cuts" user "Board Geometry/Outline")
		(27 "Margin" user)
		(31 "F.CrtYd" user "Package Geometry/Place Bound Top")
		(29 "B.CrtYd" user "Package Geometry/Place Bound Bottom")
		(35 "F.Fab" user "Ref Des/Assembly Top")
		(33 "B.Fab" user "Ref Des/Assembly Bottom")
	)
	(footprint ""
		(layer "F.Cu")
		(at 424.204892 -395.619478)
		(property "Reference" "R3437"
			(at 0 0 0)
			(layer "F.SilkS")
			(hide yes)
			(effects
				(font
					(size 1.27 1.27)
				)
			)
		)
		(property "Value" ""
			(at 0 0 0)
			(layer "F.Fab")
			(effects
				(font
					(size 1.27 1.27)
				)
			)
		)
		(duplicate_pad_numbers_are_jumpers no)
		(fp_line
			(start -0.7874 -0.4064)
			(end 0.7874 -0.4064)
			(stroke
				(width 0.1524)
				(type default)
			)
			(layer "F.SilkS")
		)
		(fp_line
			(start -0.7874 0.4064)
			(end -0.7874 -0.4064)
			(stroke
				(width 0.1524)
				(type default)
			)
			(layer "F.SilkS")
		)
		(fp_line
			(start 0.7874 -0.4064)
			(end 0.7874 0.4064)
			(stroke
				(width 0.1524)
				(type default)
			)
			(layer "F.SilkS")
		)
		(fp_line
			(start 0.7874 0.4064)
			(end -0.7874 0.4064)
			(stroke
				(width 0.1524)
				(type default)
			)
			(layer "F.SilkS")
		)
		(fp_line
			(start -0.67945 -0.305054)
			(end -0.12065 -0.305054)
			(stroke
				(width 0.1)
				(type default)
			)
			(layer "F.Fab")
		)
		(fp_line
			(start -0.67945 0.3048)
			(end -0.67945 -0.305054)
			(stroke
				(width 0.1)
				(type default)
			)
			(layer "F.Fab")
		)
		(fp_line
			(start -0.12065 -0.305054)
			(end -0.12065 -0.2794)
			(stroke
				(width 0.1)
				(type default)
			)
			(layer "F.Fab")
		)
		(fp_line
			(start -0.12065 -0.2794)
			(end 0.12065 -0.2794)
			(stroke
				(width 0.1)
				(type default)
			)
			(layer "F.Fab")
		)
		(fp_line
			(start -0.12065 0.2794)
			(end -0.12065 0.3048)
			(stroke
				(width 0.1)
				(type default)
			)
			(layer "F.Fab")
		)
		(fp_line
			(start -0.12065 0.3048)
			(end -0.67945 0.3048)
			(stroke
				(width 0.1)
				(type default)
			)
			(layer "F.Fab")
		)
		(fp_line
			(start 0.120396 0.2794)
			(end -0.12065 0.2794)
			(stroke
				(width 0.1)
				(type default)
			)
			(layer "F.Fab")
		)
		(fp_line
			(start 0.120396 0.3048)
			(end 0.120396 0.2794)
			(stroke
				(width 0.1)
				(type default)
			)
			(layer "F.Fab")
		)
		(fp_line
			(start 0.12065 -0.3048)
			(end 0.67945 -0.3048)
			(stroke
				(width 0.1)
				(type default)
			)
			(layer "F.Fab")
		)
		(fp_line
			(start 0.12065 -0.2794)
			(end 0.12065 -0.3048)
			(stroke
				(width 0.1)
				(type default)
			)
			(layer "F.Fab")
		)
		(fp_line
			(start 0.67945 -0.3048)
			(end 0.67945 0.3048)
			(stroke
				(width 0.1)
				(type default)
			)
			(layer "F.Fab")
		)
		(fp_line
			(start 0.67945 0.3048)
			(end 0.120396 0.3048)
			(stroke
				(width 0.1)
				(type default)
			)
			(layer "F.Fab")
		)
		(pad "1" smd circle
			(at -0.40005 0)
			(size 0 0)
			(layers "F.Cu" "F.Mask" "F.Paste")
			(net "P3V3_AUX")
		)
		(pad "2" smd circle
			(at 0.40005 0)
			(size 0 0)
			(layers "F.Cu" "F.Mask" "F.Paste")
			(net "GPU_FPGA_OVERT_ISO_N")
		)
	)
	(footprint ""
		(layer "F.Cu")
		(at 23.890478 -17.623536 90)
		(property "Reference" "C812"
			(at 0 0 90)
			(layer "F.SilkS")
			(hide yes)
			(effects
				(font
					(size 1.27 1.27)
				)
			)
		)
		(property "Value" ""
			(at 0 0 90)
			(layer "F.Fab")
			(effects
				(font
					(size 1.27 1.27)
				)
			)
		)
		(duplicate_pad_numbers_are_jumpers no)
		(fp_line
			(start 0.299974 -0.150114)
			(end 0.299974 0.150114)
			(stroke
				(width 0.1)
				(type default)
			)
			(layer "F.Fab")
		)
		(fp_line
			(start -0.299974 -0.150114)
			(end 0.299974 -0.150114)
			(stroke
				(width 0.1)
				(type default)
			)
			(layer "F.Fab")
		)
		(fp_line
			(start 0.299974 0.150114)
			(end -0.299974 0.150114)
			(stroke
				(width 0.1)
				(type default)
			)
			(layer "F.Fab")
		)
		(fp_line
			(start -0.299974 0.150114)
			(end -0.299974 -0.150114)
			(stroke
				(width 0.1)
				(type default)
			)
			(layer "F.Fab")
		)
		(pad "1" smd rect
			(at -0.2667 0 90)
			(size 0.3048 0.381)
			(layers "F.Cu" "F.Mask" "F.Paste")
			(net "P5E_CPU1_PE1_TX_C_DN<12>")
		)
		(pad "2" smd rect
			(at 0.2667 0 90)
			(size 0.3048 0.381)
			(layers "F.Cu" "F.Mask" "F.Paste")
			(net "P5E_CPU1_PE1_TX_DN<12>")
		)
	)
	(footprint ""
		(layer "F.Cu")
		(at 356.616 -415.127948)
		(property "Reference" "R4561"
			(at 0 0 0)
			(layer "F.SilkS")
			(hide yes)
			(effects
				(font
					(size 1.27 1.27)
				)
			)
		)
		(property "Value" ""
			(at 0 0 0)
			(layer "F.Fab")
			(effects
				(font
					(size 1.27 1.27)
				)
			)
		)
		(duplicate_pad_numbers_are_jumpers no)
		(fp_line
			(start -0.7874 -0.4064)
			(end 0.7874 -0.4064)
			(stroke
				(width 0.1524)
				(type default)
			)
			(layer "F.SilkS")
		)
		(fp_line
			(start -0.7874 0.4064)
			(end -0.7874 -0.4064)
			(stroke
				(width 0.1524)
				(type default)
			)
			(layer "F.SilkS")
		)
		(fp_line
			(start 0.7874 -0.4064)
			(end 0.7874 0.4064)
			(stroke
				(width 0.1524)
				(type default)
			)
			(layer "F.SilkS")
		)
		(fp_line
			(start 0.7874 0.4064)
			(end -0.7874 0.4064)
			(stroke
				(width 0.1524)
				(type default)
			)
			(layer "F.SilkS")
		)
		(fp_line
			(start -0.67945 -0.305054)
			(end -0.12065 -0.305054)
			(stroke
				(width 0.1)
				(type default)
			)
			(layer "F.Fab")
		)
		(fp_line
			(start -0.67945 0.3048)
			(end -0.67945 -0.305054)
			(stroke
				(width 0.1)
				(type default)
			)
			(layer "F.Fab")
		)
		(fp_line
			(start -0.12065 -0.305054)
			(end -0.12065 -0.2794)
			(stroke
				(width 0.1)
				(type default)
			)
			(layer "F.Fab")
		)
		(fp_line
			(start -0.12065 -0.2794)
			(end 0.12065 -0.2794)
			(stroke
				(width 0.1)
				(type default)
			)
			(layer "F.Fab")
		)
		(fp_line
			(start -0.12065 0.2794)
			(end -0.12065 0.3048)
			(stroke
				(width 0.1)
				(type default)
			)
			(layer "F.Fab")
		)
		(fp_line
			(start -0.12065 0.3048)
			(end -0.67945 0.3048)
			(stroke
				(width 0.1)
				(type default)
			)
			(layer "F.Fab")
		)
		(fp_line
			(start 0.120396 0.2794)
			(end -0.12065 0.2794)
			(stroke
				(width 0.1)
				(type default)
			)
			(layer "F.Fab")
		)
		(fp_line
			(start 0.120396 0.3048)
			(end 0.120396 0.2794)
			(stroke
				(width 0.1)
				(type default)
			)
			(layer "F.Fab")
		)
		(fp_line
			(start 0.12065 -0.3048)
			(end 0.67945 -0.3048)
			(stroke
				(width 0.1)
				(type default)
			)
			(layer "F.Fab")
		)
		(fp_line
			(start 0.12065 -0.2794)
			(end 0.12065 -0.3048)
			(stroke
				(width 0.1)
				(type default)
			)
			(layer "F.Fab")
		)
		(fp_line
			(start 0.67945 -0.3048)
			(end 0.67945 0.3048)
			(stroke
				(width 0.1)
				(type default)
			)
			(layer "F.Fab")
		)
		(fp_line
			(start 0.67945 0.3048)
			(end 0.120396 0.3048)
			(stroke
				(width 0.1)
				(type default)
			)
			(layer "F.Fab")
		)
		(pad "1" smd circle
			(at -0.40005 0)
			(size 0 0)
			(layers "F.Cu" "F.Mask" "F.Paste")
			(net "P3V3_AUX")
		)
		(pad "2" smd circle
			(at 0.40005 0)
			(size 0 0)
			(layers "F.Cu" "F.Mask" "F.Paste")
			(net "SWB_HSC_PWRGD_ISO")
		)
	)
	(footprint ""
		(layer "F.Cu")
		(at 36.956238 -131.77774 180)
		(property "Reference" "R2561"
			(at 0 0 180)
			(layer "F.SilkS")
			(hide yes)
			(effects
				(font
					(size 1.27 1.27)
				)
			)
		)
		(property "Value" ""
			(at 0 0 180)
			(layer "F.Fab")
			(effects
				(font
					(size 1.27 1.27)
				)
			)
		)
		(duplicate_pad_numbers_are_jumpers no)
		(fp_line
			(start 0.7874 0.4064)
			(end -0.7874 0.4064)
			(stroke
				(width 0.1524)
				(type default)
			)
			(layer "F.SilkS")
		)
		(fp_line
			(start 0.7874 -0.4064)
			(end 0.7874 0.4064)
			(stroke
				(width 0.1524)
				(type default)
			)
			(layer "F.SilkS")
		)
		(fp_line
			(start -0.7874 0.4064)
			(end -0.7874 -0.4064)
			(stroke
				(width 0.1524)
				(type default)
			)
			(layer "F.SilkS")
		)
		(fp_line
			(start -0.7874 -0.4064)
			(end 0.7874 -0.4064)
			(stroke
				(width 0.1524)
				(type default)
			)
			(layer "F.SilkS")
		)
		(fp_line
			(start 0.67945 0.3048)
			(end 0.120396 0.3048)
			(stroke
				(width 0.1)
				(type default)
			)
			(layer "F.Fab")
		)
		(fp_line
			(start 0.67945 -0.3048)
			(end 0.67945 0.3048)
			(stroke
				(width 0.1)
				(type default)
			)
			(layer "F.Fab")
		)
		(fp_line
			(start 0.12065 -0.2794)
			(end 0.12065 -0.3048)
			(stroke
				(width 0.1)
				(type default)
			)
			(layer "F.Fab")
		)
		(fp_line
			(start 0.12065 -0.3048)
			(end 0.67945 -0.3048)
			(stroke
				(width 0.1)
				(type default)
			)
			(layer "F.Fab")
		)
		(fp_line
			(start 0.120396 0.3048)
			(end 0.120396 0.2794)
			(stroke
				(width 0.1)
				(type default)
			)
			(layer "F.Fab")
		)
		(fp_line
			(start 0.120396 0.2794)
			(end -0.12065 0.2794)
			(stroke
				(width 0.1)
				(type default)
			)
			(layer "F.Fab")
		)
		(fp_line
			(start -0.12065 0.3048)
			(end -0.67945 0.3048)
			(stroke
				(width 0.1)
				(type default)
			)
			(layer "F.Fab")
		)
		(fp_line
			(start -0.12065 0.2794)
			(end -0.12065 0.3048)
			(stroke
				(width 0.1)
				(type default)
			)
			(layer "F.Fab")
		)
		(fp_line
			(start -0.12065 -0.2794)
			(end 0.12065 -0.2794)
			(stroke
				(width 0.1)
				(type default)
			)
			(layer "F.Fab")
		)
		(fp_line
			(start -0.12065 -0.305054)
			(end -0.12065 -0.2794)
			(stroke
				(width 0.1)
				(type default)
			)
			(layer "F.Fab")
		)
		(fp_line
			(start -0.67945 0.3048)
			(end -0.67945 -0.305054)
			(stroke
				(width 0.1)
				(type default)
			)
			(layer "F.Fab")
		)
		(fp_line
			(start -0.67945 -0.305054)
			(end -0.12065 -0.305054)
			(stroke
				(width 0.1)
				(type default)
			)
			(layer "F.Fab")
		)
		(pad "1" smd circle
			(at -0.40005 0 180)
			(size 0 0)
			(layers "F.Cu" "F.Mask" "F.Paste")
			(net "SVID_ALERT0_CPU1_R_N")
		)
		(pad "2" smd circle
			(at 0.40005 0 180)
			(size 0 0)
			(layers "F.Cu" "F.Mask" "F.Paste")
			(net "SVID_ALERT_PVCCINFAON_CPU1_R")
		)
	)
	(footprint ""
		(layer "F.Cu")
		(at 157.02788 -112.486948)
		(property "Reference" "R3481"
			(at 0 0 0)
			(layer "F.SilkS")
			(hide yes)
			(effects
				(font
					(size 1.27 1.27)
				)
			)
		)
		(property "Value" ""
			(at 0 0 0)
			(layer "F.Fab")
			(effects
				(font
					(size 1.27 1.27)
				)
			)
		)
		(duplicate_pad_numbers_are_jumpers no)
		(fp_line
			(start -0.7874 -0.4064)
			(end 0.7874 -0.4064)
			(stroke
				(width 0.1524)
				(type default)
			)
			(layer "F.SilkS")
		)
		(fp_line
			(start -0.7874 0.4064)
			(end -0.7874 -0.4064)
			(stroke
				(width 0.1524)
				(type default)
			)
			(layer "F.SilkS")
		)
		(fp_line
			(start 0.7874 -0.4064)
			(end 0.7874 0.4064)
			(stroke
				(width 0.1524)
				(type default)
			)
			(layer "F.SilkS")
		)
		(fp_line
			(start 0.7874 0.4064)
			(end -0.7874 0.4064)
			(stroke
				(width 0.1524)
				(type default)
			)
			(layer "F.SilkS")
		)
		(fp_line
			(start -0.67945 -0.305054)
			(end -0.12065 -0.305054)
			(stroke
				(width 0.1)
				(type default)
			)
			(layer "F.Fab")
		)
		(fp_line
			(start -0.67945 0.3048)
			(end -0.67945 -0.305054)
			(stroke
				(width 0.1)
				(type default)
			)
			(layer "F.Fab")
		)
		(fp_line
			(start -0.12065 -0.305054)
			(end -0.12065 -0.2794)
			(stroke
				(width 0.1)
				(type default)
			)
			(layer "F.Fab")
		)
		(fp_line
			(start -0.12065 -0.2794)
			(end 0.12065 -0.2794)
			(stroke
				(width 0.1)
				(type default)
			)
			(layer "F.Fab")
		)
		(fp_line
			(start -0.12065 0.2794)
			(end -0.12065 0.3048)
			(stroke
				(width 0.1)
				(type default)
			)
			(layer "F.Fab")
		)
		(fp_line
			(start -0.12065 0.3048)
			(end -0.67945 0.3048)
			(stroke
				(width 0.1)
				(type default)
			)
			(layer "F.Fab")
		)
		(fp_line
			(start 0.120396 0.2794)
			(end -0.12065 0.2794)
			(stroke
				(width 0.1)
				(type default)
			)
			(layer "F.Fab")
		)
		(fp_line
			(start 0.120396 0.3048)
			(end 0.120396 0.2794)
			(stroke
				(width 0.1)
				(type default)
			)
			(layer "F.Fab")
		)
		(fp_line
			(start 0.12065 -0.3048)
			(end 0.67945 -0.3048)
			(stroke
				(width 0.1)
				(type default)
			)
			(layer "F.Fab")
		)
		(fp_line
			(start 0.12065 -0.2794)
			(end 0.12065 -0.3048)
			(stroke
				(width 0.1)
				(type default)
			)
			(layer "F.Fab")
		)
		(fp_line
			(start 0.67945 -0.3048)
			(end 0.67945 0.3048)
			(stroke
				(width 0.1)
				(type default)
			)
			(layer "F.Fab")
		)
		(fp_line
			(start 0.67945 0.3048)
			(end 0.120396 0.3048)
			(stroke
				(width 0.1)
				(type default)
			)
			(layer "F.Fab")
		)
		(pad "1" smd circle
			(at -0.40005 0)
			(size 0 0)
			(layers "F.Cu" "F.Mask" "F.Paste")
			(net "GPU_HMC_PRSNT_ISO_N")
		)
		(pad "2" smd circle
			(at 0.40005 0)
			(size 0 0)
			(layers "F.Cu" "F.Mask" "F.Paste")
			(net "GPU_HMC_PRSNT_ISO_R_N")
		)
	)
	(footprint ""
		(layer "F.Cu")
		(at 369.2652 -407.67)
		(property "Reference" "Q153"
			(at -1.8288 -3.086608 0)
			(unlocked yes)
			(layer "F.SilkS")
			(effects
				(font
					(size 0.7874 0.5842)
					(thickness 0.1524)
				)
				(justify left)
			)
		)
		(property "Value" ""
			(at 0 0 0)
			(layer "F.Fab")
			(effects
				(font
					(size 1.27 1.27)
				)
			)
		)
		(duplicate_pad_numbers_are_jumpers no)
		(fp_line
			(start -1.332738 -1.100074)
			(end -0.4826 -1.100074)
			(stroke
				(width 0.1524)
				(type default)
			)
			(layer "F.SilkS")
		)
		(fp_line
			(start -1.332738 1.100074)
			(end -1.332738 -1.100074)
			(stroke
				(width 0.1524)
				(type default)
			)
			(layer "F.SilkS")
		)
		(fp_line
			(start -0.4826 -1.100074)
			(end 0 -0.541274)
			(stroke
				(width 0.1524)
				(type default)
			)
			(layer "F.SilkS")
		)
		(fp_line
			(start 0 -0.541274)
			(end 0.4826 -1.100074)
			(stroke
				(width 0.1524)
				(type default)
			)
			(layer "F.SilkS")
		)
		(fp_line
			(start 0.4826 -1.100074)
			(end 1.332738 -1.100074)
			(stroke
				(width 0.1524)
				(type default)
			)
			(layer "F.SilkS")
		)
		(fp_line
			(start 1.332738 -1.100074)
			(end 1.332738 1.100074)
			(stroke
				(width 0.1524)
				(type default)
			)
			(layer "F.SilkS")
		)
		(fp_line
			(start 1.332738 1.100074)
			(end -1.332738 1.100074)
			(stroke
				(width 0.1524)
				(type default)
			)
			(layer "F.SilkS")
		)
		(fp_poly
			(pts
				(xy -1.804924 -1.575816) (xy -1.308608 -2.072386) (xy -1.060196 -1.327658)
			)
			(stroke
				(width 0)
				(type default)
			)
			(fill yes)
			(layer "F.SilkS")
		)
		(fp_line
			(start -0.674878 -1.100074)
			(end 0.674878 -1.100074)
			(stroke
				(width 0.1)
				(type default)
			)
			(layer "F.Fab")
		)
		(fp_line
			(start -0.674878 1.100074)
			(end -0.674878 -1.100074)
			(stroke
				(width 0.1)
				(type default)
			)
			(layer "F.Fab")
		)
		(fp_line
			(start 0.674878 -1.100074)
			(end 0.674878 1.100074)
			(stroke
				(width 0.1)
				(type default)
			)
			(layer "F.Fab")
		)
		(fp_line
			(start 0.674878 1.100074)
			(end -0.674878 1.100074)
			(stroke
				(width 0.1)
				(type default)
			)
			(layer "F.Fab")
		)
		(fp_poly
			(pts
				(xy -2.2352 -0.298958) (xy -2.2352 -1.001014) (xy -1.533144 -0.649986)
			)
			(stroke
				(width 0)
				(type default)
			)
			(fill yes)
			(layer "F.Fab")
		)
		(pad "1" smd rect
			(at -0.94996 -0.649986 90)
			(size 0.4318 0.508)
			(layers "F.Cu" "F.Mask" "F.Paste")
			(net "GND")
		)
		(pad "2" smd rect
			(at -0.94996 0 90)
			(size 0.4318 0.508)
			(layers "F.Cu" "F.Mask" "F.Paste")
			(net "PRSNT_CABLE_SWB_B1_N")
		)
		(pad "3" smd rect
			(at -0.94996 0.649986 90)
			(size 0.4318 0.508)
			(layers "F.Cu" "F.Mask" "F.Paste")
			(net "PRSNT_CABLE_SWB_B1_ISO_N")
		)
		(pad "4" smd rect
			(at 0.94996 0.649986 90)
			(size 0.4318 0.508)
			(layers "F.Cu" "F.Mask" "F.Paste")
			(net "GND")
		)
		(pad "5" smd rect
			(at 0.94996 0 90)
			(size 0.4318 0.508)
			(layers "F.Cu" "F.Mask" "F.Paste")
			(net "PRSNT_CABLE_SWB_B1")
		)
		(pad "6" smd rect
			(at 0.94996 -0.649986 90)
			(size 0.4318 0.508)
			(layers "F.Cu" "F.Mask" "F.Paste")
			(net "PRSNT_CABLE_SWB_B1")
		)
	)
)
